(kicad_pcb
	(version 20260206)
	(generator "pcbnew")
	(generator_version "10.0")
	(general
		(thickness 1.6)
		(legacy_teardrops no)
	)
	(paper "A4")
	(title_block
		(title "Wiwynn_Tioga_Pass_MB.brd")
		(comment 1 "Tioga Pass / footprints 895-902 of 4770")
	)
	(layers
		(0 "F.Cu" signal "TOP")
		(4 "In1.Cu" signal "L2GND")
		(6 "In2.Cu" signal "L3")
		(8 "In3.Cu" signal "L4GND")
		(10 "In4.Cu" signal "L5")
		(12 "In5.Cu" signal "L6GND")
		(14 "In6.Cu" signal "L7VCC")
		(16 "In7.Cu" signal "L8VCC")
		(18 "In8.Cu" signal "L9GND")
		(20 "In9.Cu" signal "L10")
		(22 "In10.Cu" signal "L11GND")
		(24 "In11.Cu" signal "L12")
		(26 "In12.Cu" signal "L13GND")
		(2 "B.Cu" signal "BOTTOM")
		(9 "F.Adhes" user "F.Adhesive")
		(11 "B.Adhes" user "B.Adhesive")
		(13 "F.Paste" user "Package Geometry/Pastemask Top")
		(15 "B.Paste" user "Package Geometry/Pastemask Bottom")
		(5 "F.SilkS" user "Ref Des/Silkscreen Top")
		(7 "B.SilkS" user "Ref Des/Silkscreen Bottom")
		(1 "F.Mask" user "Board Geometry/Soldermask Top")
		(3 "B.Mask" user "Board Geometry/Soldermask Bottom")
		(17 "Dwgs.User" user "User.Drawings")
		(19 "Cmts.User" user "User.Comments")
		(21 "Eco1.User" user "User.Eco1")
		(23 "Eco2.User" user "User.Eco2")
		(25 "Edge.Cuts" user "Board Geometry/Outline")
		(27 "Margin" user)
		(31 "F.CrtYd" user "Package Geometry/Place Bound Top")
		(29 "B.CrtYd" user "Package Geometry/Place Bound Bottom")
		(35 "F.Fab" user "Ref Des/Assembly Top")
		(33 "B.Fab" user "Ref Des/Assembly Bottom")
	)
	(footprint ""
		(layer "F.Cu")
		(at 194.564 -12.5095 180)
		(property "Reference" "R4G3"
			(at 0 0 180)
			(layer "F.SilkS")
			(hide yes)
			(effects
				(font
					(size 1.27 1.27)
				)
			)
		)
		(property "Value" ""
			(at 0 0 180)
			(layer "F.Fab")
			(effects
				(font
					(size 1.27 1.27)
				)
			)
		)
		(duplicate_pad_numbers_are_jumpers no)
		(fp_poly
			(pts
				(xy -0.2794 -0.1016) (xy 0.2794 -0.1016) (xy 0.2794 0.9906) (xy -0.2794 0.9906)
			)
			(stroke
				(width 0)
				(type default)
			)
			(fill no)
			(layer "F.CrtYd")
		)
		(fp_line
			(start 0.2794 0.9906)
			(end 0.2794 -0.1016)
			(stroke
				(width 0.1)
				(type default)
			)
			(layer "F.Fab")
		)
		(fp_line
			(start 0.2794 -0.1016)
			(end -0.2794 -0.1016)
			(stroke
				(width 0.1)
				(type default)
			)
			(layer "F.Fab")
		)
		(fp_line
			(start -0.2794 0.9906)
			(end 0.2794 0.9906)
			(stroke
				(width 0.1)
				(type default)
			)
			(layer "F.Fab")
		)
		(fp_line
			(start -0.2794 -0.1016)
			(end -0.2794 0.9906)
			(stroke
				(width 0.1)
				(type default)
			)
			(layer "F.Fab")
		)
		(pad "1" smd rect
			(at 0 0 180)
			(size 0.508 0.508)
			(layers "F.Cu" "F.Mask" "F.Paste")
			(net "M_B_VREF")
		)
		(pad "2" smd rect
			(at 0 0.889 180)
			(size 0.508 0.508)
			(layers "F.Cu" "F.Mask" "F.Paste")
			(net "GND")
		)
		(zone
			(layer "F.Cu")
			(hatch none 0.5)
			(connect_pads
				(clearance 0)
			)
			(min_thickness 0.25)
			(keepout
				(tracks not_allowed)
				(vias allowed)
				(pads allowed)
				(copperpour not_allowed)
				(footprints allowed)
			)
			(placement
				(enabled no)
				(sheetname "")
			)
			(fill
				(thermal_gap 0.5)
				(thermal_bridge_width 0.5)
				(island_removal_mode 0)
			)
			(polygon
				(pts
					(xy 194.818 -13.1445) (xy 194.31 -13.1445) (xy 194.31 -12.7635) (xy 194.818 -12.7635)
				)
			)
		)
		(zone
			(layer "F.Cu")
			(hatch none 0.5)
			(connect_pads
				(clearance 0)
			)
			(min_thickness 0.25)
			(keepout
				(tracks allowed)
				(vias not_allowed)
				(pads allowed)
				(copperpour not_allowed)
				(footprints allowed)
			)
			(placement
				(enabled no)
				(sheetname "")
			)
			(fill
				(thermal_gap 0.5)
				(thermal_bridge_width 0.5)
				(island_removal_mode 0)
			)
			(polygon
				(pts
					(xy 194.818 -12.7635) (xy 194.31 -12.7635) (xy 194.31 -13.1445) (xy 194.818 -13.1445)
				)
			)
		)
	)
	(footprint ""
		(layer "F.Cu")
		(at 167.6273 -133.1976)
		(property "Reference" "C4B3"
			(at 0 0 0)
			(layer "F.SilkS")
			(hide yes)
			(effects
				(font
					(size 1.27 1.27)
				)
			)
		)
		(property "Value" ""
			(at 0 0 0)
			(layer "F.Fab")
			(effects
				(font
					(size 1.27 1.27)
				)
			)
		)
		(duplicate_pad_numbers_are_jumpers no)
		(fp_poly
			(pts
				(xy -0.7239 -0.2159) (xy 0.7239 -0.2159) (xy 0.7239 1.9939) (xy -0.7239 1.9939)
			)
			(stroke
				(width 0)
				(type default)
			)
			(fill no)
			(layer "F.CrtYd")
		)
		(fp_line
			(start -0.7239 -0.2159)
			(end -0.7239 1.9939)
			(stroke
				(width 0.1)
				(type default)
			)
			(layer "F.Fab")
		)
		(fp_line
			(start -0.7239 1.9939)
			(end 0.7239 1.9939)
			(stroke
				(width 0.1)
				(type default)
			)
			(layer "F.Fab")
		)
		(fp_line
			(start 0.7239 -0.2159)
			(end -0.7239 -0.2159)
			(stroke
				(width 0.1)
				(type default)
			)
			(layer "F.Fab")
		)
		(fp_line
			(start 0.7239 1.9939)
			(end 0.7239 -0.2159)
			(stroke
				(width 0.1)
				(type default)
			)
			(layer "F.Fab")
		)
		(pad "1" smd rect
			(at 0 0)
			(size 1.27 1.016)
			(layers "F.Cu" "F.Mask" "F.Paste")
			(net "PVPP_KLM")
		)
		(pad "2" smd rect
			(at 0 1.778)
			(size 1.27 1.016)
			(layers "F.Cu" "F.Mask" "F.Paste")
			(net "GND")
		)
		(zone
			(layer "F.Cu")
			(hatch none 0.5)
			(connect_pads
				(clearance 0)
			)
			(min_thickness 0.25)
			(keepout
				(tracks not_allowed)
				(vias allowed)
				(pads allowed)
				(copperpour not_allowed)
				(footprints allowed)
			)
			(placement
				(enabled no)
				(sheetname "")
			)
			(fill
				(thermal_gap 0.5)
				(thermal_bridge_width 0.5)
				(island_removal_mode 0)
			)
			(polygon
				(pts
					(xy 166.9923 -132.6896) (xy 168.2623 -132.6896) (xy 168.2623 -131.9276) (xy 166.9923 -131.9276)
				)
			)
		)
	)
	(footprint ""
		(layer "F.Cu")
		(at 19.05 -87.63)
		(property "Reference" "R1D3"
			(at 0 0 0)
			(layer "F.SilkS")
			(hide yes)
			(effects
				(font
					(size 1.27 1.27)
				)
			)
		)
		(property "Value" ""
			(at 0 0 0)
			(layer "F.Fab")
			(effects
				(font
					(size 1.27 1.27)
				)
			)
		)
		(duplicate_pad_numbers_are_jumpers no)
		(fp_rect
			(start -0.2794 0.9906)
			(end 0.2794 -0.1016)
			(stroke
				(width 0)
				(type default)
			)
			(fill no)
			(layer "F.CrtYd")
		)
		(fp_line
			(start -0.2794 -0.1016)
			(end -0.2794 0.9906)
			(stroke
				(width 0.1)
				(type default)
			)
			(layer "F.Fab")
		)
		(fp_line
			(start -0.2794 0.9906)
			(end 0.2794 0.9906)
			(stroke
				(width 0.1)
				(type default)
			)
			(layer "F.Fab")
		)
		(fp_line
			(start 0.2794 -0.1016)
			(end -0.2794 -0.1016)
			(stroke
				(width 0.1)
				(type default)
			)
			(layer "F.Fab")
		)
		(fp_line
			(start 0.2794 0.9906)
			(end 0.2794 -0.1016)
			(stroke
				(width 0.1)
				(type default)
			)
			(layer "F.Fab")
		)
		(pad "1" smd rect
			(at 0 0)
			(size 0.508 0.508)
			(layers "F.Cu" "F.Mask" "F.Paste")
			(net "SVID_VALERT_VCCIN_CPU1")
		)
		(pad "2" smd rect
			(at 0 0.889)
			(size 0.508 0.508)
			(layers "F.Cu" "F.Mask" "F.Paste")
			(net "SVID_ALERT0_CPU1_R_N")
		)
		(zone
			(layer "F.Cu")
			(hatch none 0.5)
			(connect_pads
				(clearance 0)
			)
			(min_thickness 0.25)
			(keepout
				(tracks not_allowed)
				(vias allowed)
				(pads allowed)
				(copperpour not_allowed)
				(footprints allowed)
			)
			(placement
				(enabled no)
				(sheetname "")
			)
			(fill
				(thermal_gap 0.5)
				(thermal_bridge_width 0.5)
				(island_removal_mode 0)
			)
			(polygon
				(pts
					(xy 18.796 -86.995) (xy 19.304 -86.995) (xy 19.304 -87.376) (xy 18.796 -87.376)
				)
			)
		)
		(zone
			(layer "F.Cu")
			(hatch none 0.5)
			(connect_pads
				(clearance 0)
			)
			(min_thickness 0.25)
			(keepout
				(tracks allowed)
				(vias not_allowed)
				(pads allowed)
				(copperpour not_allowed)
				(footprints allowed)
			)
			(placement
				(enabled no)
				(sheetname "")
			)
			(fill
				(thermal_gap 0.5)
				(thermal_bridge_width 0.5)
				(island_removal_mode 0)
			)
			(polygon
				(pts
					(xy 18.796 -86.995) (xy 19.304 -86.995) (xy 19.304 -87.376) (xy 18.796 -87.376)
				)
			)
		)
	)
	(footprint ""
		(layer "F.Cu")
		(at 493.168686 -46.569884 180)
		(property "Reference" "C25W82"
			(at -0.8382 -0.67818 180)
			(unlocked yes)
			(layer "F.SilkS")
			(effects
				(font
					(size 0.4064 0.254)
					(thickness 0.1524)
				)
				(justify left)
			)
		)
		(property "Value" ""
			(at 0 0 180)
			(layer "F.Fab")
			(effects
				(font
					(size 1.27 1.27)
				)
			)
		)
		(duplicate_pad_numbers_are_jumpers no)
		(fp_poly
			(pts
				(xy 0.3048 -0.1016) (xy 0.3048 0.9906) (xy -0.3048 0.9906) (xy -0.3048 -0.1016)
			)
			(stroke
				(width 0)
				(type default)
			)
			(fill no)
			(layer "F.CrtYd")
		)
		(fp_line
			(start 0.3048 0.9906)
			(end 0.3048 -0.1016)
			(stroke
				(width 0.1)
				(type default)
			)
			(layer "F.Fab")
		)
		(fp_line
			(start 0.3048 -0.1016)
			(end -0.3048 -0.1016)
			(stroke
				(width 0.1)
				(type default)
			)
			(layer "F.Fab")
		)
		(fp_line
			(start -0.3048 0.9906)
			(end 0.3048 0.9906)
			(stroke
				(width 0.1)
				(type default)
			)
			(layer "F.Fab")
		)
		(fp_line
			(start -0.3048 -0.1016)
			(end -0.3048 0.9906)
			(stroke
				(width 0.1)
				(type default)
			)
			(layer "F.Fab")
		)
		(pad "1" smd rect
			(at 0 0 180)
			(size 0.508 0.508)
			(layers "F.Cu" "F.Mask" "F.Paste")
			(net "V_IO_VSYNC_J")
		)
		(pad "2" smd rect
			(at 0 0.889 180)
			(size 0.508 0.508)
			(layers "F.Cu" "F.Mask" "F.Paste")
			(net "GND")
		)
		(zone
			(layer "F.Cu")
			(hatch none 0.5)
			(connect_pads
				(clearance 0)
			)
			(min_thickness 0.25)
			(keepout
				(tracks not_allowed)
				(vias allowed)
				(pads allowed)
				(copperpour not_allowed)
				(footprints allowed)
			)
			(placement
				(enabled no)
				(sheetname "")
			)
			(fill
				(thermal_gap 0.5)
				(thermal_bridge_width 0.5)
				(island_removal_mode 0)
			)
			(polygon
				(pts
					(xy 493.422686 -47.204884) (xy 492.914686 -47.204884) (xy 492.914686 -46.823884) (xy 493.422686 -46.823884)
				)
			)
		)
		(zone
			(layer "F.Cu")
			(hatch none 0.5)
			(connect_pads
				(clearance 0)
			)
			(min_thickness 0.25)
			(keepout
				(tracks allowed)
				(vias not_allowed)
				(pads allowed)
				(copperpour not_allowed)
				(footprints allowed)
			)
			(placement
				(enabled no)
				(sheetname "")
			)
			(fill
				(thermal_gap 0.5)
				(thermal_bridge_width 0.5)
				(island_removal_mode 0)
			)
			(polygon
				(pts
					(xy 493.422686 -46.823884) (xy 492.914686 -46.823884) (xy 492.914686 -47.204884) (xy 493.422686 -47.204884)
				)
			)
		)
	)
	(footprint ""
		(layer "F.Cu")
		(at 184.785 -26.416)
		(property "Reference" "R4F2"
			(at 0 0 0)
			(layer "F.SilkS")
			(hide yes)
			(effects
				(font
					(size 1.27 1.27)
				)
			)
		)
		(property "Value" ""
			(at 0 0 0)
			(layer "F.Fab")
			(effects
				(font
					(size 1.27 1.27)
				)
			)
		)
		(duplicate_pad_numbers_are_jumpers no)
		(fp_line
			(start -0.9017 1.951736)
			(end -0.9017 0.823468)
			(stroke
				(width 0.1524)
				(type default)
			)
			(layer "F.SilkS")
		)
		(fp_line
			(start 0.9017 1.952498)
			(end 0.9017 0.853948)
			(stroke
				(width 0.1524)
				(type default)
			)
			(layer "F.SilkS")
		)
		(fp_poly
			(pts
				(xy -0.9017 3.0988) (xy 0.9017 3.0988) (xy 0.9017 -0.3048) (xy -0.9017 -0.3048)
			)
			(stroke
				(width 0)
				(type default)
			)
			(fill no)
			(layer "F.CrtYd")
		)
		(fp_line
			(start -0.9017 -0.3048)
			(end -0.9017 3.0988)
			(stroke
				(width 0.1)
				(type default)
			)
			(layer "F.Fab")
		)
		(fp_line
			(start -0.9017 3.0988)
			(end 0.9017 3.0988)
			(stroke
				(width 0.1)
				(type default)
			)
			(layer "F.Fab")
		)
		(fp_line
			(start 0.9017 -0.3048)
			(end -0.9017 -0.3048)
			(stroke
				(width 0.1)
				(type default)
			)
			(layer "F.Fab")
		)
		(fp_line
			(start 0.9017 3.0988)
			(end 0.9017 -0.3048)
			(stroke
				(width 0.1)
				(type default)
			)
			(layer "F.Fab")
		)
		(pad "1" smd rect
			(at 0 0)
			(size 1.524 1.016)
			(layers "F.Cu" "F.Mask" "F.Paste")
			(net "P12V_STBY")
		)
		(pad "2" smd rect
			(at 0 2.794)
			(size 1.524 1.016)
			(layers "F.Cu" "F.Mask" "F.Paste")
			(net "P12V_NVDIMM_ABC")
		)
		(zone
			(layer "F.Cu")
			(hatch none 0.5)
			(connect_pads
				(clearance 0)
			)
			(min_thickness 0.25)
			(keepout
				(tracks allowed)
				(vias not_allowed)
				(pads allowed)
				(copperpour not_allowed)
				(footprints allowed)
			)
			(placement
				(enabled no)
				(sheetname "")
			)
			(fill
				(thermal_gap 0.5)
				(thermal_bridge_width 0.5)
				(island_removal_mode 0)
			)
			(polygon
				(pts
					(xy 184.023 -24.13) (xy 185.547 -24.13) (xy 185.547 -25.908) (xy 184.023 -25.908)
				)
			)
		)
	)
	(footprint ""
		(layer "F.Cu")
		(at 449.69938 -32.4485 90)
		(property "Reference" "R25W26"
			(at 0 0 90)
			(layer "F.SilkS")
			(hide yes)
			(effects
				(font
					(size 1.27 1.27)
				)
			)
		)
		(property "Value" "*"
			(at 0.064008 -4.108196 90)
			(unlocked yes)
			(layer "F.Fab")
			(hide yes)
			(effects
				(font
					(size 1.27 1.016)
					(thickness 0.1524)
				)
			)
		)
		(property "Device Type" "120R2F-GP_RCL_GP-120R2F-GP,64.A"
			(at 0.064008 -5.632196 90)
			(unlocked yes)
			(layer "F.Fab")
			(hide yes)
			(effects
				(font
					(size 1.27 1.016)
					(thickness 0.1524)
				)
			)
		)
		(duplicate_pad_numbers_are_jumpers no)
		(fp_line
			(start 0.508 -0.9398)
			(end -0.508 -0.9398)
			(stroke
				(width 0.1524)
				(type default)
			)
			(layer "F.SilkS")
		)
		(fp_line
			(start -0.508 -0.9398)
			(end -0.508 0.9398)
			(stroke
				(width 0.1524)
				(type default)
			)
			(layer "F.SilkS")
		)
		(fp_rect
			(start -0.508 0.9398)
			(end 0.508 -0.9398)
			(stroke
				(width 0)
				(type default)
			)
			(fill no)
			(layer "F.CrtYd")
		)
		(fp_rect
			(start -0.508 0.9398)
			(end 0.508 -0.9398)
			(stroke
				(width 0)
				(type default)
			)
			(fill no)
			(layer "F.Fab")
		)
		(pad "1" smd custom
			(at 0 -0.4445 90)
			(size 0.1397 0.1397)
			(layers "F.Cu" "F.Mask" "F.Paste")
			(net "GND")
			(options
				(clearance outline)
				(anchor circle)
			)
			(primitives
				(gr_poly
					(pts
						(arc
							(start -0.1778 -0.2794)
							(mid -0.249642 -0.249642)
							(end -0.2794 -0.1778)
						)
						(arc
							(start -0.2794 0.1778)
							(mid -0.249642 0.249642)
							(end -0.1778 0.2794)
						)
						(arc
							(start 0.1778 0.2794)
							(mid 0.249642 0.249642)
							(end 0.2794 0.1778)
						)
						(arc
							(start 0.2794 -0.1778)
							(mid 0.249642 -0.249642)
							(end 0.1778 -0.2794)
						)
					)
					(width 0)
					(fill yes)
				)
			)
		)
		(pad "2" smd custom
			(at 0 0.4445 90)
			(size 0.1397 0.1397)
			(layers "F.Cu" "F.Mask" "F.Paste")
			(net "BMC_M_MACT_N")
			(options
				(clearance outline)
				(anchor circle)
			)
			(primitives
				(gr_poly
					(pts
						(arc
							(start -0.1778 -0.2794)
							(mid -0.249642 -0.249642)
							(end -0.2794 -0.1778)
						)
						(arc
							(start -0.2794 0.1778)
							(mid -0.249642 0.249642)
							(end -0.1778 0.2794)
						)
						(arc
							(start 0.1778 0.2794)
							(mid 0.249642 0.249642)
							(end 0.2794 0.1778)
						)
						(arc
							(start 0.2794 -0.1778)
							(mid 0.249642 -0.249642)
							(end 0.1778 -0.2794)
						)
					)
					(width 0)
					(fill yes)
				)
			)
		)
	)
	(footprint ""
		(layer "F.Cu")
		(at 1.315212 -150.678896 90)
		(property "Reference" "C1A20"
			(at 0 0 90)
			(layer "F.SilkS")
			(hide yes)
			(effects
				(font
					(size 1.27 1.27)
				)
			)
		)
		(property "Value" ""
			(at 0 0 90)
			(layer "F.Fab")
			(effects
				(font
					(size 1.27 1.27)
				)
			)
		)
		(duplicate_pad_numbers_are_jumpers no)
		(fp_rect
			(start 0.3048 -0.1016)
			(end -0.3048 0.9906)
			(stroke
				(width 0)
				(type default)
			)
			(fill no)
			(layer "F.CrtYd")
		)
		(fp_line
			(start 0.3048 -0.1016)
			(end -0.3048 -0.1016)
			(stroke
				(width 0.1)
				(type default)
			)
			(layer "F.Fab")
		)
		(fp_line
			(start -0.3048 -0.1016)
			(end -0.3048 0.9906)
			(stroke
				(width 0.1)
				(type default)
			)
			(layer "F.Fab")
		)
		(fp_line
			(start 0.3048 0.9906)
			(end 0.3048 -0.1016)
			(stroke
				(width 0.1)
				(type default)
			)
			(layer "F.Fab")
		)
		(fp_line
			(start -0.3048 0.9906)
			(end 0.3048 0.9906)
			(stroke
				(width 0.1)
				(type default)
			)
			(layer "F.Fab")
		)
		(pad "1" smd rect
			(at 0 0 90)
			(size 0.508 0.508)
			(layers "F.Cu" "F.Mask" "F.Paste")
			(net "VR_FET_SW_P12V_STBY_PVDDQ_KLM")
		)
		(pad "2" smd rect
			(at 0 0.889 90)
			(size 0.508 0.508)
			(layers "F.Cu" "F.Mask" "F.Paste")
			(net "GND")
		)
		(zone
			(layer "F.Cu")
			(hatch none 0.5)
			(connect_pads
				(clearance 0)
			)
			(min_thickness 0.25)
			(keepout
				(tracks allowed)
				(vias not_allowed)
				(pads allowed)
				(copperpour not_allowed)
				(footprints allowed)
			)
			(placement
				(enabled no)
				(sheetname "")
			)
			(fill
				(thermal_gap 0.5)
				(thermal_bridge_width 0.5)
				(island_removal_mode 0)
			)
			(polygon
				(pts
					(xy 1.569212 -150.932896) (xy 1.569212 -150.424896) (xy 1.950212 -150.424896) (xy 1.950212 -150.932896)
				)
			)
		)
		(zone
			(layer "F.Cu")
			(hatch none 0.5)
			(connect_pads
				(clearance 0)
			)
			(min_thickness 0.25)
			(keepout
				(tracks not_allowed)
				(vias allowed)
				(pads allowed)
				(copperpour not_allowed)
				(footprints allowed)
			)
			(placement
				(enabled no)
				(sheetname "")
			)
			(fill
				(thermal_gap 0.5)
				(thermal_bridge_width 0.5)
				(island_removal_mode 0)
			)
			(polygon
				(pts
					(xy 1.569212 -150.932896) (xy 1.569212 -150.424896) (xy 1.950212 -150.424896) (xy 1.950212 -150.932896)
				)
			)
		)
	)
	(footprint ""
		(layer "F.Cu")
		(at 98.18624 -77.636116)
		(property "Reference" "C2D23"
			(at 0 0 0)
			(layer "F.SilkS")
			(hide yes)
			(effects
				(font
					(size 1.27 1.27)
				)
			)
		)
		(property "Value" ""
			(at 0 0 0)
			(layer "F.Fab")
			(effects
				(font
					(size 1.27 1.27)
				)
			)
		)
		(duplicate_pad_numbers_are_jumpers no)
		(fp_poly
			(pts
				(xy -0.4953 -0.2032) (xy 0.4953 -0.2032) (xy 0.4953 1.6002) (xy -0.4953 1.6002)
			)
			(stroke
				(width 0)
				(type default)
			)
			(fill no)
			(layer "F.CrtYd")
		)
		(fp_line
			(start -0.4953 -0.2032)
			(end 0.4953 -0.2032)
			(stroke
				(width 0.1)
				(type default)
			)
			(layer "F.Fab")
		)
		(fp_line
			(start -0.4953 1.6002)
			(end -0.4953 -0.2032)
			(stroke
				(width 0.1)
				(type default)
			)
			(layer "F.Fab")
		)
		(fp_line
			(start 0.4953 -0.2032)
			(end 0.4953 1.6002)
			(stroke
				(width 0.1)
				(type default)
			)
			(layer "F.Fab")
		)
		(fp_line
			(start 0.4953 1.6002)
			(end -0.4953 1.6002)
			(stroke
				(width 0.1)
				(type default)
			)
			(layer "F.Fab")
		)
		(pad "1" smd rect
			(at 0 0)
			(size 0.762 0.889)
			(layers "F.Cu" "F.Mask" "F.Paste")
			(net "PVCCIN_CPU1")
		)
		(pad "2" smd rect
			(at 0 1.397)
			(size 0.762 0.889)
			(layers "F.Cu" "F.Mask" "F.Paste")
			(net "GND")
		)
		(zone
			(layer "F.Cu")
			(hatch none 0.5)
			(connect_pads
				(clearance 0)
			)
			(min_thickness 0.25)
			(keepout
				(tracks not_allowed)
				(vias allowed)
				(pads allowed)
				(copperpour not_allowed)
				(footprints allowed)
			)
			(placement
				(enabled no)
				(sheetname "")
			)
			(fill
				(thermal_gap 0.5)
				(thermal_bridge_width 0.5)
				(island_removal_mode 0)
			)
			(polygon
				(pts
					(xy 97.80524 -77.191616) (xy 98.56724 -77.191616) (xy 98.56724 -76.683616) (xy 97.80524 -76.683616)
				)
			)
		)
	)
)
